# S9S_MB_2U (Grand Teton) — schematic netlist excerpt (pin names and nets, part order shuffled) for the footprints in the layout excerpt that follows; sources: Cadence DE-HDL packaged netlist, KiCad conversion of 03242023_DA0F0TMBIJ0_F0T_Motherboard_J_brd_V01_OCP.brd

C5232  Q_CAP  0.1UF 25V 10% EMPTY  pkg 0402  page 152 : A = PD_U5201_RSTN ; B = GND
C531  Q_CAP  47UF 4V 20% X6S  pkg C0805  page 76 : A = PVCCINFAON_CPU0 ; B = GND
R697  Q_RES  33.2 1% CHIP  pkg 0402LF  page 182 : A = FM_BMC_RSTBTN_OUT_N ; B = RST_PCH_RSTBTN_R_N

(kicad_pcb
	(version 20260206)
	(generator "pcbnew")
	(generator_version "10.0")
	(general
		(thickness 1.6)
		(legacy_teardrops no)
	)
	(paper "A4")
	(title_block
		(title "03242023_DA0F0TMBIJ0_F0T_Motherboard_J_brd_V01_OCP.brd")
		(comment 1 "Grand Teton / footprints 5518-5520 of 6105")
	)
	(layers
		(0 "F.Cu" signal "TOP")
		(4 "In1.Cu" signal "GND")
		(6 "In2.Cu" signal "IN1")
		(8 "In3.Cu" signal "GND1")
		(10 "In4.Cu" signal "IN2")
		(12 "In5.Cu" signal "GND2")
		(14 "In6.Cu" signal "IN3")
		(16 "In7.Cu" signal "GND3")
		(18 "In8.Cu" signal "VCC")
		(20 "In9.Cu" signal "VCC1")
		(22 "In10.Cu" signal "GND4")
		(24 "In11.Cu" signal "IN4")
		(26 "In12.Cu" signal "GND5")
		(28 "In13.Cu" signal "IN5")
		(30 "In14.Cu" signal "GND6")
		(32 "In15.Cu" signal "IN6")
		(34 "In16.Cu" signal "GND7")
		(2 "B.Cu" signal "BOTTOM")
		(9 "F.Adhes" user "F.Adhesive")
		(11 "B.Adhes" user "B.Adhesive")
		(13 "F.Paste" user "Package Geometry/Pastemask Top")
		(15 "B.Paste" user "Package Geometry/Pastemask Bottom")
		(5 "F.SilkS" user "Ref Des/Silkscreen Top")
		(7 "B.SilkS" user "Ref Des/Silkscreen Bottom")
		(1 "F.Mask" user "Board Geometry/Soldermask Top")
		(3 "B.Mask" user "Board Geometry/Soldermask Bottom")
		(17 "Dwgs.User" user "User.Drawings")
		(19 "Cmts.User" user "User.Comments")
		(21 "Eco1.User" user "User.Eco1")
		(23 "Eco2.User" user "User.Eco2")
		(25 "Edge.Cuts" user "Board Geometry/Outline")
		(27 "Margin" user)
		(31 "F.CrtYd" user "Package Geometry/Place Bound Top")
		(29 "B.CrtYd" user "Package Geometry/Place Bound Bottom")
		(35 "F.Fab" user "Ref Des/Assembly Top")
		(33 "B.Fab" user "Ref Des/Assembly Bottom")
	)
	(footprint ""
		(layer "B.Cu")
		(at 317.756032 -39.358062 -135)
		(property "Reference" "R697"
			(at 0 0 45)
			(layer "B.SilkS")
			(hide yes)
			(effects
				(font
					(size 1.27 1.27)
				)
				(justify mirror)
			)
		)
		(property "Value" ""
			(at 0 0 45)
			(layer "B.Fab")
			(effects
				(font
					(size 1.27 1.27)
				)
				(justify mirror)
			)
		)
		(duplicate_pad_numbers_are_jumpers no)
		(fp_line
			(start 0.787389 0.406267)
			(end 0.787389 -0.406267)
			(stroke
				(width 0.1524)
				(type default)
			)
			(layer "B.SilkS")
		)
		(fp_line
			(start 0.787389 -0.406267)
			(end -0.787389 -0.406267)
			(stroke
				(width 0.1524)
				(type default)
			)
			(layer "B.SilkS")
		)
		(fp_line
			(start -0.787389 0.406267)
			(end 0.787389 0.406267)
			(stroke
				(width 0.1524)
				(type default)
			)
			(layer "B.SilkS")
		)
		(fp_line
			(start -0.787389 -0.406267)
			(end -0.787389 0.406267)
			(stroke
				(width 0.1524)
				(type default)
			)
			(layer "B.SilkS")
		)
		(fp_line
			(start 0.679446 0.30479)
			(end 0.679446 -0.305149)
			(stroke
				(width 0.1)
				(type default)
			)
			(layer "B.Fab")
		)
		(fp_line
			(start 0.120515 0.30479)
			(end 0.679446 0.30479)
			(stroke
				(width 0.1)
				(type default)
			)
			(layer "B.Fab")
		)
		(fp_line
			(start 0.120695 0.279466)
			(end 0.120515 0.30479)
			(stroke
				(width 0.1)
				(type default)
			)
			(layer "B.Fab")
		)
		(fp_line
			(start 0.679446 -0.305149)
			(end 0.120695 -0.304969)
			(stroke
				(width 0.1)
				(type default)
			)
			(layer "B.Fab")
		)
		(fp_line
			(start -0.120515 0.30479)
			(end -0.120335 0.279466)
			(stroke
				(width 0.1)
				(type default)
			)
			(layer "B.Fab")
		)
		(fp_line
			(start -0.120335 0.279466)
			(end 0.120695 0.279466)
			(stroke
				(width 0.1)
				(type default)
			)
			(layer "B.Fab")
		)
		(fp_line
			(start 0.120695 -0.279466)
			(end -0.120695 -0.279466)
			(stroke
				(width 0.1)
				(type default)
			)
			(layer "B.Fab")
		)
		(fp_line
			(start 0.120695 -0.304969)
			(end 0.120695 -0.279466)
			(stroke
				(width 0.1)
				(type default)
			)
			(layer "B.Fab")
		)
		(fp_line
			(start -0.679446 0.30479)
			(end -0.120515 0.30479)
			(stroke
				(width 0.1)
				(type default)
			)
			(layer "B.Fab")
		)
		(fp_line
			(start -0.120695 -0.279466)
			(end -0.120515 -0.30479)
			(stroke
				(width 0.1)
				(type default)
			)
			(layer "B.Fab")
		)
		(fp_line
			(start -0.120515 -0.30479)
			(end -0.679446 -0.30479)
			(stroke
				(width 0.1)
				(type default)
			)
			(layer "B.Fab")
		)
		(fp_line
			(start -0.679446 -0.30479)
			(end -0.679446 0.30479)
			(stroke
				(width 0.1)
				(type default)
			)
			(layer "B.Fab")
		)
		(pad "1" smd circle
			(at 0.40005 0 45)
			(size 0 0)
			(layers "B.Cu" "B.Mask" "B.Paste")
			(net "FM_BMC_RSTBTN_OUT_N")
		)
		(pad "2" smd circle
			(at -0.40005 0 45)
			(size 0 0)
			(layers "B.Cu" "B.Mask" "B.Paste")
			(net "RST_PCH_RSTBTN_R_N")
		)
	)
	(footprint ""
		(layer "B.Cu")
		(at 8.19277 -112.04702)
		(property "Reference" "C5232"
			(at 0 0 0)
			(layer "B.SilkS")
			(hide yes)
			(effects
				(font
					(size 1.27 1.27)
				)
				(justify mirror)
			)
		)
		(property "Value" ""
			(at 0 0 0)
			(layer "B.Fab")
			(effects
				(font
					(size 1.27 1.27)
				)
				(justify mirror)
			)
		)
		(duplicate_pad_numbers_are_jumpers no)
		(fp_line
			(start -0.7874 -0.4064)
			(end -0.7874 0.4064)
			(stroke
				(width 0.1524)
				(type default)
			)
			(layer "B.SilkS")
		)
		(fp_line
			(start -0.7874 0.4064)
			(end 0.7874 0.4064)
			(stroke
				(width 0.1524)
				(type default)
			)
			(layer "B.SilkS")
		)
		(fp_line
			(start 0.7874 -0.4064)
			(end -0.7874 -0.4064)
			(stroke
				(width 0.1524)
				(type default)
			)
			(layer "B.SilkS")
		)
		(fp_line
			(start 0.7874 0.4064)
			(end 0.7874 -0.4064)
			(stroke
				(width 0.1524)
				(type default)
			)
			(layer "B.SilkS")
		)
		(fp_line
			(start -0.67945 -0.3048)
			(end -0.67945 0.3048)
			(stroke
				(width 0.1)
				(type default)
			)
			(layer "B.Fab")
		)
		(fp_line
			(start -0.67945 0.3048)
			(end -0.120396 0.3048)
			(stroke
				(width 0.1)
				(type default)
			)
			(layer "B.Fab")
		)
		(fp_line
			(start -0.12065 -0.3048)
			(end -0.67945 -0.3048)
			(stroke
				(width 0.1)
				(type default)
			)
			(layer "B.Fab")
		)
		(fp_line
			(start -0.12065 -0.2794)
			(end -0.12065 -0.3048)
			(stroke
				(width 0.1)
				(type default)
			)
			(layer "B.Fab")
		)
		(fp_line
			(start -0.120396 0.2794)
			(end 0.12065 0.2794)
			(stroke
				(width 0.1)
				(type default)
			)
			(layer "B.Fab")
		)
		(fp_line
			(start -0.120396 0.3048)
			(end -0.120396 0.2794)
			(stroke
				(width 0.1)
				(type default)
			)
			(layer "B.Fab")
		)
		(fp_line
			(start 0.12065 -0.305054)
			(end 0.12065 -0.2794)
			(stroke
				(width 0.1)
				(type default)
			)
			(layer "B.Fab")
		)
		(fp_line
			(start 0.12065 -0.2794)
			(end -0.12065 -0.2794)
			(stroke
				(width 0.1)
				(type default)
			)
			(layer "B.Fab")
		)
		(fp_line
			(start 0.12065 0.2794)
			(end 0.12065 0.3048)
			(stroke
				(width 0.1)
				(type default)
			)
			(layer "B.Fab")
		)
		(fp_line
			(start 0.12065 0.3048)
			(end 0.67945 0.3048)
			(stroke
				(width 0.1)
				(type default)
			)
			(layer "B.Fab")
		)
		(fp_line
			(start 0.67945 -0.305054)
			(end 0.12065 -0.305054)
			(stroke
				(width 0.1)
				(type default)
			)
			(layer "B.Fab")
		)
		(fp_line
			(start 0.67945 0.3048)
			(end 0.67945 -0.305054)
			(stroke
				(width 0.1)
				(type default)
			)
			(layer "B.Fab")
		)
		(pad "1" smd circle
			(at 0.40005 0 180)
			(size 0 0)
			(layers "B.Cu" "B.Mask" "B.Paste")
			(net "PD_U5201_RSTN")
		)
		(pad "2" smd circle
			(at -0.40005 0 180)
			(size 0 0)
			(layers "B.Cu" "B.Mask" "B.Paste")
			(net "GND")
		)
	)
	(footprint ""
		(layer "B.Cu")
		(at 369.52174 -212.049614 180)
		(property "Reference" "C531"
			(at 0 0 0)
			(layer "B.SilkS")
			(hide yes)
			(effects
				(font
					(size 1.27 1.27)
				)
				(justify mirror)
			)
		)
		(property "Value" ""
			(at 0 0 0)
			(layer "B.Fab")
			(effects
				(font
					(size 1.27 1.27)
				)
				(justify mirror)
			)
		)
		(duplicate_pad_numbers_are_jumpers no)
		(fp_line
			(start 1.524 0.762)
			(end 1.524 -0.762)
			(stroke
				(width 0.1524)
				(type default)
			)
			(layer "B.SilkS")
		)
		(fp_line
			(start 1.524 -0.762)
			(end -1.524 -0.762)
			(stroke
				(width 0.1524)
				(type default)
			)
			(layer "B.SilkS")
		)
		(fp_line
			(start -1.524 0.762)
			(end 1.524 0.762)
			(stroke
				(width 0.1524)
				(type default)
			)
			(layer "B.SilkS")
		)
		(fp_line
			(start -1.524 -0.762)
			(end -1.524 0.762)
			(stroke
				(width 0.1524)
				(type default)
			)
			(layer "B.SilkS")
		)
		(fp_line
			(start 1.1049 0.724916)
			(end -1.1049 0.724916)
			(stroke
				(width 0.1)
				(type default)
			)
			(layer "B.Fab")
		)
		(fp_line
			(start 1.1049 -0.724916)
			(end 1.1049 0.724916)
			(stroke
				(width 0.1)
				(type default)
			)
			(layer "B.Fab")
		)
		(fp_line
			(start -1.1049 0.724916)
			(end -1.1049 -0.724916)
			(stroke
				(width 0.1)
				(type default)
			)
			(layer "B.Fab")
		)
		(fp_line
			(start -1.1049 -0.724916)
			(end 1.1049 -0.724916)
			(stroke
				(width 0.1)
				(type default)
			)
			(layer "B.Fab")
		)
		(pad "1" smd rect
			(at 0.889 0 180)
			(size 1.016 1.27)
			(layers "B.Cu" "B.Mask" "B.Paste")
			(net "PVCCINFAON_CPU0")
		)
		(pad "2" smd rect
			(at -0.889 0 180)
			(size 1.016 1.27)
			(layers "B.Cu" "B.Mask" "B.Paste")
			(net "GND")
		)
	)
)
